# T6G (Grand Teton) — schematic netlist excerpt (pin names and nets, part order shuffled) for the footprints in the layout excerpt that follows; sources: Cadence DE-HDL packaged netlist, KiCad conversion of 04192023_DAF0TMB3IC0_F0TG_MB_C_brd_V02_OCP.brd

C272  Q_CAP  22UF 4V 20% X6S  pkg C0402  page 69 : A = PVDDCR_CPU0_P0 ; B = GND
C6607  Q_CAP_DIFFBUS  DIFF BUS_0.22UF 6.3V 20% X6S  pkg C0201  page 308 : \1\ = P5E_CPU0_P3_TX_BUF_C_DP<5> ; \2\ = P5E_CPU0_P3_TX_BUF_DP<5>
C2381  Q_CAP  22UF 4V 20% X6S  pkg C0402  page 73 : A = PVDDCR_CPU1_P1 ; B = GND

(kicad_pcb
	(version 20260206)
	(generator "pcbnew")
	(generator_version "10.0")
	(general
		(thickness 1.6)
		(legacy_teardrops no)
	)
	(paper "A4")
	(title_block
		(title "04192023_DAF0TMB3IC0_F0TG_MB_C_brd_V02_OCP.brd")
		(comment 1 "Grand Teton / footprints 6593-6595 of 8354")
	)
	(layers
		(0 "F.Cu" signal "TOP")
		(4 "In1.Cu" signal "GND")
		(6 "In2.Cu" signal "IN1")
		(8 "In3.Cu" signal "GND1")
		(10 "In4.Cu" signal "IN2")
		(12 "In5.Cu" signal "GND2")
		(14 "In6.Cu" signal "IN3")
		(16 "In7.Cu" signal "GND3")
		(18 "In8.Cu" signal "VCC")
		(20 "In9.Cu" signal "VCC1")
		(22 "In10.Cu" signal "GND4")
		(24 "In11.Cu" signal "IN4")
		(26 "In12.Cu" signal "GND5")
		(28 "In13.Cu" signal "IN5")
		(30 "In14.Cu" signal "GND6")
		(32 "In15.Cu" signal "IN6")
		(34 "In16.Cu" signal "GND7")
		(2 "B.Cu" signal "BOTTOM")
		(9 "F.Adhes" user "F.Adhesive")
		(11 "B.Adhes" user "B.Adhesive")
		(13 "F.Paste" user "Package Geometry/Pastemask Top")
		(15 "B.Paste" user "Package Geometry/Pastemask Bottom")
		(5 "F.SilkS" user "Ref Des/Silkscreen Top")
		(7 "B.SilkS" user "Ref Des/Silkscreen Bottom")
		(1 "F.Mask" user "Board Geometry/Soldermask Top")
		(3 "B.Mask" user "Board Geometry/Soldermask Bottom")
		(17 "Dwgs.User" user "User.Drawings")
		(19 "Cmts.User" user "User.Comments")
		(21 "Eco1.User" user "User.Eco1")
		(23 "Eco2.User" user "User.Eco2")
		(25 "Edge.Cuts" user "Board Geometry/Outline")
		(27 "Margin" user)
		(31 "F.CrtYd" user "Package Geometry/Place Bound Top")
		(29 "B.CrtYd" user "Package Geometry/Place Bound Bottom")
		(35 "F.Fab" user "Ref Des/Assembly Top")
		(33 "B.Fab" user "Ref Des/Assembly Bottom")
	)
	(footprint ""
		(layer "B.Cu")
		(at 373.329454 -249.36831)
		(property "Reference" "C272"
			(at 0 0 0)
			(layer "B.SilkS")
			(hide yes)
			(effects
				(font
					(size 1.27 1.27)
				)
				(justify mirror)
			)
		)
		(property "Value" ""
			(at 0 0 0)
			(layer "B.Fab")
			(effects
				(font
					(size 1.27 1.27)
				)
				(justify mirror)
			)
		)
		(duplicate_pad_numbers_are_jumpers no)
		(fp_line
			(start -0.7874 -0.4064)
			(end -0.7874 0.4064)
			(stroke
				(width 0.1524)
				(type default)
			)
			(layer "B.SilkS")
		)
		(fp_line
			(start -0.7874 0.4064)
			(end 0.7874 0.4064)
			(stroke
				(width 0.1524)
				(type default)
			)
			(layer "B.SilkS")
		)
		(fp_line
			(start 0.7874 -0.4064)
			(end -0.7874 -0.4064)
			(stroke
				(width 0.1524)
				(type default)
			)
			(layer "B.SilkS")
		)
		(fp_line
			(start 0.7874 0.4064)
			(end 0.7874 -0.4064)
			(stroke
				(width 0.1524)
				(type default)
			)
			(layer "B.SilkS")
		)
		(fp_line
			(start -0.67945 -0.3048)
			(end -0.67945 0.3048)
			(stroke
				(width 0.1)
				(type default)
			)
			(layer "B.Fab")
		)
		(fp_line
			(start -0.67945 0.3048)
			(end -0.120396 0.3048)
			(stroke
				(width 0.1)
				(type default)
			)
			(layer "B.Fab")
		)
		(fp_line
			(start -0.12065 -0.3048)
			(end -0.67945 -0.3048)
			(stroke
				(width 0.1)
				(type default)
			)
			(layer "B.Fab")
		)
		(fp_line
			(start -0.12065 -0.2794)
			(end -0.12065 -0.3048)
			(stroke
				(width 0.1)
				(type default)
			)
			(layer "B.Fab")
		)
		(fp_line
			(start -0.120396 0.2794)
			(end 0.12065 0.2794)
			(stroke
				(width 0.1)
				(type default)
			)
			(layer "B.Fab")
		)
		(fp_line
			(start -0.120396 0.3048)
			(end -0.120396 0.2794)
			(stroke
				(width 0.1)
				(type default)
			)
			(layer "B.Fab")
		)
		(fp_line
			(start 0.12065 -0.305054)
			(end 0.12065 -0.2794)
			(stroke
				(width 0.1)
				(type default)
			)
			(layer "B.Fab")
		)
		(fp_line
			(start 0.12065 -0.2794)
			(end -0.12065 -0.2794)
			(stroke
				(width 0.1)
				(type default)
			)
			(layer "B.Fab")
		)
		(fp_line
			(start 0.12065 0.2794)
			(end 0.12065 0.3048)
			(stroke
				(width 0.1)
				(type default)
			)
			(layer "B.Fab")
		)
		(fp_line
			(start 0.12065 0.3048)
			(end 0.67945 0.3048)
			(stroke
				(width 0.1)
				(type default)
			)
			(layer "B.Fab")
		)
		(fp_line
			(start 0.67945 -0.305054)
			(end 0.12065 -0.305054)
			(stroke
				(width 0.1)
				(type default)
			)
			(layer "B.Fab")
		)
		(fp_line
			(start 0.67945 0.3048)
			(end 0.67945 -0.305054)
			(stroke
				(width 0.1)
				(type default)
			)
			(layer "B.Fab")
		)
		(pad "1" smd circle
			(at 0.40005 0 180)
			(size 0 0)
			(layers "B.Cu" "B.Mask" "B.Paste")
			(net "PVDDCR_CPU0_P0")
		)
		(pad "2" smd circle
			(at -0.40005 0 180)
			(size 0 0)
			(layers "B.Cu" "B.Mask" "B.Paste")
			(net "GND")
		)
	)
	(footprint ""
		(layer "B.Cu")
		(at 121.452386 -267.49883)
		(property "Reference" "C2381"
			(at 0 0 0)
			(layer "B.SilkS")
			(hide yes)
			(effects
				(font
					(size 1.27 1.27)
				)
				(justify mirror)
			)
		)
		(property "Value" ""
			(at 0 0 0)
			(layer "B.Fab")
			(effects
				(font
					(size 1.27 1.27)
				)
				(justify mirror)
			)
		)
		(duplicate_pad_numbers_are_jumpers no)
		(fp_line
			(start -0.7874 -0.4064)
			(end -0.7874 0.4064)
			(stroke
				(width 0.1524)
				(type default)
			)
			(layer "B.SilkS")
		)
		(fp_line
			(start -0.7874 0.4064)
			(end 0.7874 0.4064)
			(stroke
				(width 0.1524)
				(type default)
			)
			(layer "B.SilkS")
		)
		(fp_line
			(start 0.7874 -0.4064)
			(end -0.7874 -0.4064)
			(stroke
				(width 0.1524)
				(type default)
			)
			(layer "B.SilkS")
		)
		(fp_line
			(start 0.7874 0.4064)
			(end 0.7874 -0.4064)
			(stroke
				(width 0.1524)
				(type default)
			)
			(layer "B.SilkS")
		)
		(fp_line
			(start -0.67945 -0.3048)
			(end -0.67945 0.3048)
			(stroke
				(width 0.1)
				(type default)
			)
			(layer "B.Fab")
		)
		(fp_line
			(start -0.67945 0.3048)
			(end -0.120396 0.3048)
			(stroke
				(width 0.1)
				(type default)
			)
			(layer "B.Fab")
		)
		(fp_line
			(start -0.12065 -0.3048)
			(end -0.67945 -0.3048)
			(stroke
				(width 0.1)
				(type default)
			)
			(layer "B.Fab")
		)
		(fp_line
			(start -0.12065 -0.2794)
			(end -0.12065 -0.3048)
			(stroke
				(width 0.1)
				(type default)
			)
			(layer "B.Fab")
		)
		(fp_line
			(start -0.120396 0.2794)
			(end 0.12065 0.2794)
			(stroke
				(width 0.1)
				(type default)
			)
			(layer "B.Fab")
		)
		(fp_line
			(start -0.120396 0.3048)
			(end -0.120396 0.2794)
			(stroke
				(width 0.1)
				(type default)
			)
			(layer "B.Fab")
		)
		(fp_line
			(start 0.12065 -0.305054)
			(end 0.12065 -0.2794)
			(stroke
				(width 0.1)
				(type default)
			)
			(layer "B.Fab")
		)
		(fp_line
			(start 0.12065 -0.2794)
			(end -0.12065 -0.2794)
			(stroke
				(width 0.1)
				(type default)
			)
			(layer "B.Fab")
		)
		(fp_line
			(start 0.12065 0.2794)
			(end 0.12065 0.3048)
			(stroke
				(width 0.1)
				(type default)
			)
			(layer "B.Fab")
		)
		(fp_line
			(start 0.12065 0.3048)
			(end 0.67945 0.3048)
			(stroke
				(width 0.1)
				(type default)
			)
			(layer "B.Fab")
		)
		(fp_line
			(start 0.67945 -0.305054)
			(end 0.12065 -0.305054)
			(stroke
				(width 0.1)
				(type default)
			)
			(layer "B.Fab")
		)
		(fp_line
			(start 0.67945 0.3048)
			(end 0.67945 -0.305054)
			(stroke
				(width 0.1)
				(type default)
			)
			(layer "B.Fab")
		)
		(pad "1" smd circle
			(at 0.40005 0 180)
			(size 0 0)
			(layers "B.Cu" "B.Mask" "B.Paste")
			(net "PVDDCR_CPU1_P1")
		)
		(pad "2" smd circle
			(at -0.40005 0 180)
			(size 0 0)
			(layers "B.Cu" "B.Mask" "B.Paste")
			(net "GND")
		)
	)
	(footprint ""
		(layer "B.Cu")
		(at 388.630922 -416.899344 90)
		(property "Reference" "C6607"
			(at 0 0 90)
			(layer "B.SilkS")
			(hide yes)
			(effects
				(font
					(size 1.27 1.27)
				)
				(justify mirror)
			)
		)
		(property "Value" ""
			(at 0 0 90)
			(layer "B.Fab")
			(effects
				(font
					(size 1.27 1.27)
				)
				(justify mirror)
			)
		)
		(duplicate_pad_numbers_are_jumpers no)
		(fp_line
			(start 0.299974 -0.150114)
			(end -0.299974 -0.150114)
			(stroke
				(width 0.1)
				(type default)
			)
			(layer "B.Fab")
		)
		(fp_line
			(start -0.299974 -0.150114)
			(end -0.299974 0.150114)
			(stroke
				(width 0.1)
				(type default)
			)
			(layer "B.Fab")
		)
		(fp_line
			(start 0.299974 0.150114)
			(end 0.299974 -0.150114)
			(stroke
				(width 0.1)
				(type default)
			)
			(layer "B.Fab")
		)
		(fp_line
			(start -0.299974 0.150114)
			(end 0.299974 0.150114)
			(stroke
				(width 0.1)
				(type default)
			)
			(layer "B.Fab")
		)
		(pad "1" smd rect
			(at 0.2667 0 270)
			(size 0.3048 0.381)
			(layers "B.Cu" "B.Mask" "B.Paste")
			(net "P5E_CPU0_P3_TX_BUF_C_DP<5>")
		)
		(pad "2" smd rect
			(at -0.2667 0 270)
			(size 0.3048 0.381)
			(layers "B.Cu" "B.Mask" "B.Paste")
			(net "P5E_CPU0_P3_TX_BUF_DP<5>")
		)
	)
)
